(kicad_pcb
	(version 20240108)
	(generator "pcbnew")
	(generator_version "8.0")
	(general
		(thickness 1.62)
		(legacy_teardrops no)
	)
	(paper "A4")
	(title_block
		(title "Jetson Orin Baseboard")
		(date "2025-03-12")
		(rev "1.3.4")
		(company "Antmicro Ltd")
		(comment 1 "www.antmicro.com")
		(comment 9 "footprints 174-176 of 677")
	)
	(layers
		(0 "F.Cu" signal)
		(1 "In1.Cu" signal)
		(2 "In2.Cu" signal)
		(3 "In3.Cu" signal)
		(4 "In4.Cu" jumper)
		(5 "In5.Cu" signal)
		(6 "In6.Cu" signal)
		(31 "B.Cu" signal)
		(32 "B.Adhes" user "B.Adhesive")
		(33 "F.Adhes" user "F.Adhesive")
		(34 "B.Paste" user)
		(35 "F.Paste" user)
		(36 "B.SilkS" user "B.Silkscreen")
		(37 "F.SilkS" user "F.Silkscreen")
		(38 "B.Mask" user)
		(39 "F.Mask" user)
		(40 "Dwgs.User" user "User.Drawings")
		(41 "Cmts.User" user "User.Comments")
		(42 "Eco1.User" user "User.Eco1")
		(43 "Eco2.User" user "User.Eco2")
		(44 "Edge.Cuts" user)
		(45 "Margin" user)
		(46 "B.CrtYd" user "B.Courtyard")
		(47 "F.CrtYd" user "F.Courtyard")
		(48 "B.Fab" user)
		(49 "F.Fab" user)
	)
	(footprint "antmicro-footprints:SOT-23-3"
		(layer "F.Cu")
		(at 58.2 112.6 -90)
		(property "Reference" "Q15"
			(at 1.825 2.725 0)
			(layer "F.SilkS")
			(effects
				(font
					(size 0.7 0.7)
					(thickness 0.15)
				)
				(justify left bottom)
			)
		)
		(property "Value" "SSM3J332R"
			(at -1.9 2.7 -90)
			(layer "F.Fab")
			(effects
				(font
					(size 0.7 0.7)
					(thickness 0.15)
				)
				(justify left bottom)
			)
		)
		(property "Footprint" "antmicro-footprints:SOT-23-3"
			(at 0 0 -90)
			(layer "F.Fab")
			(hide yes)
			(effects
				(font
					(size 1.27 1.27)
					(thickness 0.15)
				)
			)
		)
		(property "Datasheet" "https://www.mouser.com/datasheet/2/408/SSM3J332R_datasheet_en_20181015-1150575.pdf"
			(at 0 0 -90)
			(layer "F.Fab")
			(hide yes)
			(effects
				(font
					(size 1.27 1.27)
					(thickness 0.15)
				)
			)
		)
		(property "Author" "Antmicro"
			(at -54.4 170.8 0)
			(layer "F.Fab")
			(hide yes)
			(effects
				(font
					(size 1 1)
					(thickness 0.15)
				)
			)
		)
		(property "License" "Apache-2.0"
			(at -54.4 170.8 0)
			(layer "F.Fab")
			(hide yes)
			(effects
				(font
					(size 1 1)
					(thickness 0.15)
				)
			)
		)
		(property "MPN" "SSM3J332R,LF"
			(at -54.4 170.8 0)
			(layer "F.Fab")
			(hide yes)
			(effects
				(font
					(size 1 1)
					(thickness 0.15)
				)
			)
		)
		(property "Manufacturer" "Toshiba"
			(at -54.4 170.8 0)
			(layer "F.Fab")
			(hide yes)
			(effects
				(font
					(size 1 1)
					(thickness 0.15)
				)
			)
		)
		(sheetname "Supply")
		(sheetfile "supply.kicad_sch")
		(attr smd)
		(fp_line
			(start -0.7 1.5)
			(end -0.7 1.35)
			(stroke
				(width 0.15)
				(type solid)
			)
			(layer "F.SilkS")
		)
		(fp_line
			(start 0.7 1.5)
			(end -0.7 1.5)
			(stroke
				(width 0.15)
				(type solid)
			)
			(layer "F.SilkS")
		)
		(fp_line
			(start 0.7 0.4)
			(end 0.7 1.5)
			(stroke
				(width 0.15)
				(type solid)
			)
			(layer "F.SilkS")
		)
		(fp_line
			(start 0.7 -0.4)
			(end 0.7 -1.5)
			(stroke
				(width 0.15)
				(type solid)
			)
			(layer "F.SilkS")
		)
		(fp_line
			(start -1.45 -1.35)
			(end -0.85 -1.35)
			(stroke
				(width 0.15)
				(type solid)
			)
			(layer "F.SilkS")
		)
		(fp_line
			(start -0.85 -1.35)
			(end -0.7 -1.5)
			(stroke
				(width 0.15)
				(type solid)
			)
			(layer "F.SilkS")
		)
		(fp_line
			(start 0.7 -1.5)
			(end -0.7 -1.5)
			(stroke
				(width 0.15)
				(type solid)
			)
			(layer "F.SilkS")
		)
		(fp_line
			(start -0.85 1.65)
			(end -0.85 1.4)
			(stroke
				(width 0.05)
				(type solid)
			)
			(layer "F.CrtYd")
		)
		(fp_line
			(start 0.85 1.65)
			(end -0.85 1.65)
			(stroke
				(width 0.05)
				(type solid)
			)
			(layer "F.CrtYd")
		)
		(fp_line
			(start -1.75 1.4)
			(end -1.75 0.5)
			(stroke
				(width 0.05)
				(type solid)
			)
			(layer "F.CrtYd")
		)
		(fp_line
			(start -0.85 1.4)
			(end -1.75 1.4)
			(stroke
				(width 0.05)
				(type solid)
			)
			(layer "F.CrtYd")
		)
		(fp_line
			(start -1.75 0.5)
			(end -0.85 0.5)
			(stroke
				(width 0.05)
				(type solid)
			)
			(layer "F.CrtYd")
		)
		(fp_line
			(start -0.85 0.5)
			(end -0.85 -0.5)
			(stroke
				(width 0.05)
				(type solid)
			)
			(layer "F.CrtYd")
		)
		(fp_line
			(start 0.85 0.45)
			(end 0.85 1.65)
			(stroke
				(width 0.05)
				(type solid)
			)
			(layer "F.CrtYd")
		)
		(fp_line
			(start 1.75 0.45)
			(end 0.85 0.45)
			(stroke
				(width 0.05)
				(type solid)
			)
			(layer "F.CrtYd")
		)
		(fp_line
			(start 0.825 -0.45)
			(end 1.75 -0.45)
			(stroke
				(width 0.05)
				(type solid)
			)
			(layer "F.CrtYd")
		)
		(fp_line
			(start 1.75 -0.45)
			(end 1.75 0.45)
			(stroke
				(width 0.05)
				(type solid)
			)
			(layer "F.CrtYd")
		)
		(fp_line
			(start -1.75 -0.5)
			(end -1.75 -1.4)
			(stroke
				(width 0.05)
				(type solid)
			)
			(layer "F.CrtYd")
		)
		(fp_line
			(start -0.85 -0.5)
			(end -1.75 -0.5)
			(stroke
				(width 0.05)
				(type solid)
			)
			(layer "F.CrtYd")
		)
		(fp_line
			(start -0.9 -1.4)
			(end -1.75 -1.4)
			(stroke
				(width 0.05)
				(type solid)
			)
			(layer "F.CrtYd")
		)
		(fp_line
			(start -0.9 -1.6)
			(end -0.9 -1.4)
			(stroke
				(width 0.05)
				(type solid)
			)
			(layer "F.CrtYd")
		)
		(fp_line
			(start -0.9 -1.6)
			(end 0.825 -1.6)
			(stroke
				(width 0.05)
				(type solid)
			)
			(layer "F.CrtYd")
		)
		(fp_line
			(start 0.825 -1.6)
			(end 0.825 -0.45)
			(stroke
				(width 0.05)
				(type solid)
			)
			(layer "F.CrtYd")
		)
		(fp_line
			(start -0.712 1.519)
			(end 0.688 1.519)
			(stroke
				(width 0.15)
				(type solid)
			)
			(layer "F.Fab")
		)
		(fp_line
			(start 0.688 1.519)
			(end 0.688 -1.52)
			(stroke
				(width 0.15)
				(type solid)
			)
			(layer "F.Fab")
		)
		(fp_line
			(start -0.712 -1.325)
			(end -0.712 1.523)
			(stroke
				(width 0.15)
				(type solid)
			)
			(layer "F.Fab")
		)
		(fp_line
			(start -0.437 -1.526)
			(end -0.712 -1.325)
			(stroke
				(width 0.15)
				(type solid)
			)
			(layer "F.Fab")
		)
		(fp_line
			(start -0.437 -1.526)
			(end 0.688 -1.526)
			(stroke
				(width 0.15)
				(type solid)
			)
			(layer "F.Fab")
		)
		(fp_text user "Author: Antmicro"
			(at -1.837 5.3 -90)
			(layer "F.Fab")
			(hide yes)
			(effects
				(font
					(size 0.7 0.7)
					(thickness 0.15)
				)
				(justify left bottom)
			)
		)
		(fp_text user "License: Apache-2.0"
			(at -1.8 6.8 -90)
			(layer "F.Fab")
			(hide yes)
			(effects
				(font
					(size 0.7 0.7)
					(thickness 0.15)
				)
				(justify left bottom)
			)
		)
		(fp_text user "${REFERENCE}"
			(at -1.837 4 -90)
			(layer "F.Fab")
			(hide yes)
			(effects
				(font
					(size 0.7 0.7)
					(thickness 0.15)
				)
				(justify left bottom)
			)
		)
		(pad "1" smd roundrect
			(at -1.1 -0.951 270)
			(size 1 0.6)
			(layers "F.Cu" "F.Paste" "F.Mask")
			(roundrect_rratio 0.15)
			(net 630 "Net-(Q15-G)")
			(pinfunction "G")
			(pintype "bidirectional")
		)
		(pad "2" smd roundrect
			(at -1.1 0.949 270)
			(size 1 0.6)
			(layers "F.Cu" "F.Paste" "F.Mask")
			(roundrect_rratio 0.15)
			(net 328 "/Supply/VCC_IN")
			(pinfunction "S")
			(pintype "bidirectional")
		)
		(pad "3" smd roundrect
			(at 1.1 -0.0005 270)
			(size 1 0.6)
			(layers "F.Cu" "F.Paste" "F.Mask")
			(roundrect_rratio 0.15)
			(net 189 "Net-(D28-C)")
			(pinfunction "D")
			(pintype "bidirectional")
		)
	)
	(footprint "antmicro-footprints:R_Array_4x0402"
		(layer "F.Cu")
		(at 147.85 103.12 -90)
		(property "Reference" "R101"
			(at 1.44 -1.6 -90)
			(layer "F.SilkS")
			(effects
				(font
					(size 0.7 0.7)
					(thickness 0.15)
				)
				(justify left bottom)
			)
		)
		(property "Value" "R_4x330R_0402_array"
			(at -1.5 2 -90)
			(layer "F.Fab")
			(effects
				(font
					(size 0.7 0.7)
					(thickness 0.15)
				)
				(justify left bottom)
			)
		)
		(property "Footprint" "antmicro-footprints:R_Array_4x0402"
			(at 0 0 -90)
			(layer "F.Fab")
			(hide yes)
			(effects
				(font
					(size 1.27 1.27)
					(thickness 0.15)
				)
			)
		)
		(property "Datasheet" "http://industrial.panasonic.com/cdbs/www-data/pdf/AOC0000/AOC0000C14.pdf"
			(at 0 0 -90)
			(layer "F.Fab")
			(hide yes)
			(effects
				(font
					(size 1.27 1.27)
					(thickness 0.15)
				)
			)
		)
		(property "Author" "Antmicro"
			(at 44.73 250.97 0)
			(layer "F.Fab")
			(hide yes)
			(effects
				(font
					(size 1 1)
					(thickness 0.15)
				)
			)
		)
		(property "License" "Apache-2.0"
			(at 44.73 250.97 0)
			(layer "F.Fab")
			(hide yes)
			(effects
				(font
					(size 1 1)
					(thickness 0.15)
				)
			)
		)
		(property "MPN" "EXB-28V331JX"
			(at 44.73 250.97 0)
			(layer "F.Fab")
			(hide yes)
			(effects
				(font
					(size 1 1)
					(thickness 0.15)
				)
			)
		)
		(property "Manufacturer" "Panasonic"
			(at 44.73 250.97 0)
			(layer "F.Fab")
			(hide yes)
			(effects
				(font
					(size 1 1)
					(thickness 0.15)
				)
			)
		)
		(property "Val" "R_4x330R_0402"
			(at 44.73 250.97 0)
			(layer "F.Fab")
			(hide yes)
			(effects
				(font
					(size 1 1)
					(thickness 0.15)
				)
			)
		)
		(sheetname "Peripherals")
		(sheetfile "peripherals.kicad_sch")
		(attr smd)
		(fp_line
			(start 1.167 0.498)
			(end 1.167 -0.5)
			(stroke
				(width 0.15)
				(type solid)
			)
			(layer "F.SilkS")
		)
		(fp_line
			(start -1.17 -0.5)
			(end -1.17 0.498)
			(stroke
				(width 0.15)
				(type solid)
			)
			(layer "F.SilkS")
		)
		(fp_rect
			(start -1.2 -0.9)
			(end 1.2 0.9)
			(stroke
				(width 0.05)
				(type solid)
			)
			(fill none)
			(layer "F.CrtYd")
		)
		(fp_line
			(start -1 0.498)
			(end -1 -0.5)
			(stroke
				(width 0.15)
				(type solid)
			)
			(layer "F.Fab")
		)
		(fp_line
			(start 0.998 0.498)
			(end -1 0.498)
			(stroke
				(width 0.15)
				(type solid)
			)
			(layer "F.Fab")
		)
		(fp_line
			(start -1 -0.5)
			(end 0.998 -0.5)
			(stroke
				(width 0.15)
				(type solid)
			)
			(layer "F.Fab")
		)
		(fp_line
			(start 0.998 -0.5)
			(end 0.998 0.498)
			(stroke
				(width 0.15)
				(type solid)
			)
			(layer "F.Fab")
		)
		(fp_text user "License: Apache-2.0"
			(at -1.5 5.75 -90)
			(layer "F.Fab")
			(hide yes)
			(effects
				(font
					(size 0.7 0.7)
					(thickness 0.15)
				)
				(justify left bottom)
			)
		)
		(fp_text user "Author: Antmicro"
			(at -1.5 4.5 -90)
			(layer "F.Fab")
			(hide yes)
			(effects
				(font
					(size 0.7 0.7)
					(thickness 0.15)
				)
				(justify left bottom)
			)
		)
		(fp_text user "${REFERENCE}"
			(at -1.5 3.25 -90)
			(layer "F.Fab")
			(hide yes)
			(effects
				(font
					(size 0.7 0.7)
					(thickness 0.15)
				)
				(justify left bottom)
			)
		)
		(pad "1" smd roundrect
			(at -0.802 0.45 270)
			(size 0.4 0.5)
			(layers "F.Cu" "F.Paste" "F.Mask")
			(roundrect_rratio 0.25)
			(net 588 "/Peripherals/I2S0_SDOUT_CONN")
			(pinfunction "R1.1")
			(pintype "passive")
		)
		(pad "2" smd roundrect
			(at -0.272 0.45 270)
			(size 0.4 0.5)
			(layers "F.Cu" "F.Paste" "F.Mask")
			(roundrect_rratio 0.25)
			(net 590 "/Peripherals/SPI1_SCK_CONN")
			(pinfunction "R2.1")
			(pintype "passive")
		)
		(pad "3" smd roundrect
			(at 0.27 0.45 270)
			(size 0.4 0.5)
			(layers "F.Cu" "F.Paste" "F.Mask")
			(roundrect_rratio 0.25)
			(net 592 "/Peripherals/SPI1_MOSI_CONN")
			(pinfunction "R3.1")
			(pintype "passive")
		)
		(pad "4" smd roundrect
			(at 0.8 0.45 270)
			(size 0.4 0.5)
			(layers "F.Cu" "F.Paste" "F.Mask")
			(roundrect_rratio 0.25)
			(net 594 "/Peripherals/SPI1_MISO_CONN")
			(pinfunction "R4.1")
			(pintype "passive")
		)
		(pad "5" smd roundrect
			(at 0.8 -0.452 270)
			(size 0.4 0.5)
			(layers "F.Cu" "F.Paste" "F.Mask")
			(roundrect_rratio 0.25)
			(net 39 "SPI1_MISO")
			(pinfunction "R4.2")
			(pintype "passive")
		)
		(pad "6" smd roundrect
			(at 0.27 -0.452 270)
			(size 0.4 0.5)
			(layers "F.Cu" "F.Paste" "F.Mask")
			(roundrect_rratio 0.25)
			(net 37 "SPI1_MOSI")
			(pinfunction "R3.2")
			(pintype "passive")
		)
		(pad "7" smd roundrect
			(at -0.272 -0.452 270)
			(size 0.4 0.5)
			(layers "F.Cu" "F.Paste" "F.Mask")
			(roundrect_rratio 0.25)
			(net 38 "SPI1_SCK")
			(pinfunction "R2.2")
			(pintype "passive")
		)
		(pad "8" smd roundrect
			(at -0.802 -0.452 270)
			(size 0.4 0.5)
			(layers "F.Cu" "F.Paste" "F.Mask")
			(roundrect_rratio 0.25)
			(net 70 "I2S0_SDOUT")
			(pinfunction "R1.2")
			(pintype "passive")
		)
	)
	(footprint "antmicro-footprints:XDFN-2_1x0.60mm"
		(layer "F.Cu")
		(at 135.1 88.47 90)
		(property "Reference" "D43"
			(at -0.6 0.4 0)
			(layer "F.SilkS")
			(effects
				(font
					(size 0.7 0.7)
					(thickness 0.15)
				)
				(justify left bottom)
			)
		)
		(property "Value" "TPD1E0B04_XDFN-2"
			(at 0 1.5 90)
			(layer "F.Fab")
			(effects
				(font
					(size 0.7 0.7)
					(thickness 0.15)
				)
				(justify left bottom)
			)
		)
		(property "Footprint" "antmicro-footprints:XDFN-2_1x0.60mm"
			(at 0 0 90)
			(layer "F.Fab")
			(hide yes)
			(effects
				(font
					(size 1.27 1.27)
					(thickness 0.15)
				)
			)
		)
		(property "Datasheet" "https://www.ti.com/general/docs/suppproductinfo.tsp?distId=26&gotoUrl=https://www.ti.com/lit/gpn/tpd1e0b04"
			(at 0 0 90)
			(layer "F.Fab")
			(hide yes)
			(effects
				(font
					(size 1.27 1.27)
					(thickness 0.15)
				)
			)
		)
		(property "MPN" "TPD1E0B04DPYR"
			(at 223.57 -46.63 0)
			(layer "F.Fab")
			(hide yes)
			(effects
				(font
					(size 1 1)
					(thickness 0.15)
				)
			)
		)
		(property "Manufacturer" "Texas Instruments"
			(at 223.57 -46.63 0)
			(layer "F.Fab")
			(hide yes)
			(effects
				(font
					(size 1 1)
					(thickness 0.15)
				)
			)
		)
		(property "Author" "Antmicro"
			(at 223.57 -46.63 0)
			(layer "F.Fab")
			(hide yes)
			(effects
				(font
					(size 1 1)
					(thickness 0.15)
				)
			)
		)
		(property "License" "Apache-2.0"
			(at 223.57 -46.63 0)
			(layer "F.Fab")
			(hide yes)
			(effects
				(font
					(size 1 1)
					(thickness 0.15)
				)
			)
		)
		(sheetname "Peripherals")
		(sheetfile "peripherals.kicad_sch")
		(attr smd)
		(fp_rect
			(start -0.725 -0.475)
			(end 0.725 0.475)
			(stroke
				(width 0.05)
				(type solid)
			)
			(fill none)
			(layer "F.CrtYd")
		)
		(fp_rect
			(start -0.55 -0.35)
			(end 0.55 0.35)
			(stroke
				(width 0.15)
				(type solid)
			)
			(fill none)
			(layer "F.Fab")
		)
		(fp_text user "License: Apache-2.0"
			(at -0.8 5.6 90)
			(layer "F.Fab")
			(hide yes)
			(effects
				(font
					(size 0.7 0.7)
					(thickness 0.15)
				)
				(justify left bottom)
			)
		)
		(fp_text user "Author: Antmicro"
			(at -0.8 4.4 90)
			(layer "F.Fab")
			(hide yes)
			(effects
				(font
					(size 0.7 0.7)
					(thickness 0.15)
				)
				(justify left bottom)
			)
		)
		(fp_text user "${REFERENCE}"
			(at -0.8 3.2 90)
			(layer "F.Fab")
			(hide yes)
			(effects
				(font
					(size 0.7 0.7)
					(thickness 0.15)
				)
				(justify left bottom)
			)
		)
		(pad "1" smd roundrect
			(at -0.351 0 90)
			(size 0.3 0.5)
			(layers "F.Cu" "F.Paste" "F.Mask")
			(roundrect_rratio 0.25)
			(net 163 "PCIE2_CLK_N")
			(pinfunction "C")
			(pintype "passive")
		)
		(pad "2" smd roundrect
			(at 0.349 0 90)
			(size 0.3 0.5)
			(layers "F.Cu" "F.Paste" "F.Mask")
			(roundrect_rratio 0.25)
			(net 1 "GND")
			(pinfunction "A")
			(pintype "passive")
		)
	)
)
